(kicad_pcb
	(version 20241229)
	(generator "pcbnew")
	(generator_version "9.0")
	(general
		(thickness 1.61)
		(legacy_teardrops no)
	)
	(paper "A3")
	(title_block
		(title "RDIMM DDR5 Tester")
		(date "2026-05-21")
		(rev "2.2.0")
		(company "Antmicro")
		(comment 9 "footprints 249-252 of 796")
	)
	(layers
		(0 "F.Cu" signal)
		(4 "In1.Cu" power)
		(6 "In2.Cu" mixed)
		(8 "In3.Cu" power)
		(10 "In4.Cu" mixed)
		(12 "In5.Cu" power)
		(14 "In6.Cu" mixed)
		(16 "In7.Cu" power)
		(18 "In8.Cu" power)
		(20 "In9.Cu" mixed)
		(22 "In10.Cu" power)
		(2 "B.Cu" signal)
		(9 "F.Adhes" user "F.Adhesive")
		(11 "B.Adhes" user "B.Adhesive")
		(13 "F.Paste" user)
		(15 "B.Paste" user)
		(5 "F.SilkS" user "F.Silkscreen")
		(7 "B.SilkS" user "B.Silkscreen")
		(1 "F.Mask" user)
		(3 "B.Mask" user)
		(17 "Dwgs.User" user "User.Drawings")
		(19 "Cmts.User" user "User.Comments")
		(21 "Eco1.User" user "User.Eco1")
		(23 "Eco2.User" user "User.Eco2")
		(25 "Edge.Cuts" user)
		(27 "Margin" user)
		(31 "F.CrtYd" user "F.Courtyard")
		(29 "B.CrtYd" user "B.Courtyard")
		(35 "F.Fab" user)
		(33 "B.Fab" user)
	)
	(footprint "antmicro-footprints:VSSOP-8_2.3x2mm_P0.5mm"
		(layer "F.Cu")
		(at 239.274499 182.749)
		(property "Reference" "U24"
			(at -1.15 2.1 0)
			(layer "F.SilkS")
			(effects
				(font
					(size 0.7 0.7)
					(thickness 0.15)
				)
				(justify left bottom)
			)
		)
		(property "Value" "TS5A3359_VSSOP"
			(at 0 2.258 0)
			(layer "F.Fab")
			(effects
				(font
					(size 0.7 0.7)
					(thickness 0.15)
				)
				(justify left bottom)
			)
		)
		(property "Datasheet" "https://www.ti.com/general/docs/suppproductinfo.tsp?distId=26&gotoUrl=http%3A%2F%2Fwww.ti.com%2Flit%2Fgpn%2Fts5a3359"
			(at 0 0 0)
			(layer "F.Fab")
			(hide yes)
			(effects
				(font
					(size 1.27 1.27)
					(thickness 0.15)
				)
			)
		)
		(property "MPN" "TS5A3359DCUR"
			(at 0 0 0)
			(unlocked yes)
			(layer "F.Fab")
			(hide yes)
			(effects
				(font
					(size 1 1)
					(thickness 0.15)
				)
			)
		)
		(property "Manufacturer" "Texas Instruments"
			(at 0 0 0)
			(unlocked yes)
			(layer "F.Fab")
			(hide yes)
			(effects
				(font
					(size 1 1)
					(thickness 0.15)
				)
			)
		)
		(property "Author" "Antmicro"
			(at 0 0 0)
			(unlocked yes)
			(layer "F.Fab")
			(hide yes)
			(effects
				(font
					(size 1 1)
					(thickness 0.15)
				)
			)
		)
		(property "License" "Apache-2.0"
			(at 0 0 0)
			(unlocked yes)
			(layer "F.Fab")
			(hide yes)
			(effects
				(font
					(size 1 1)
					(thickness 0.15)
				)
			)
		)
		(sheetname "/I^{2}C + I3C/")
		(sheetfile "i2c.kicad_sch")
		(attr smd)
		(fp_line
			(start -0.82 -0.992)
			(end 0.825 -0.992)
			(stroke
				(width 0.15)
				(type solid)
			)
			(layer "F.SilkS")
		)
		(fp_line
			(start 0.825 1.007)
			(end -0.82 1.007)
			(stroke
				(width 0.15)
				(type solid)
			)
			(layer "F.SilkS")
		)
		(fp_circle
			(center -1.402 -1.192)
			(end -1.352 -1.192)
			(stroke
				(width 0.15)
				(type solid)
			)
			(fill yes)
			(layer "F.SilkS")
		)
		(fp_rect
			(start 1.8 1.35)
			(end -1.8 -1.35)
			(stroke
				(width 0.05)
				(type solid)
			)
			(fill no)
			(layer "F.CrtYd")
		)
		(fp_line
			(start -0.7 -0.99)
			(end -1.14 -0.55)
			(stroke
				(width 0.15)
				(type solid)
			)
			(layer "F.Fab")
		)
		(fp_rect
			(start -1.147 -0.992)
			(end 1.151 1.007)
			(stroke
				(width 0.15)
				(type solid)
			)
			(fill no)
			(layer "F.Fab")
		)
		(fp_text user "${REFERENCE}"
			(at -1.8 4.006 0)
			(layer "F.Fab")
			(effects
				(font
					(size 0.7 0.7)
					(thickness 0.15)
				)
				(justify left bottom)
			)
		)
		(fp_text user "Author: Antmicro"
			(at -1.8 5.208 0)
			(layer "F.Fab")
			(effects
				(font
					(size 0.7 0.7)
					(thickness 0.15)
				)
				(justify left bottom)
			)
		)
		(fp_text user "License: Apache-2.0"
			(at -1.8 6.408 0)
			(layer "F.Fab")
			(effects
				(font
					(size 0.7 0.7)
					(thickness 0.15)
				)
				(justify left bottom)
			)
		)
		(pad "1" smd rect
			(at -1.372 -0.742)
			(size 0.75 0.4)
			(layers "F.Cu" "F.Mask" "F.Paste")
			(net 465 "/FPGA banks HD/FPGA_DDR.SCL")
			(pinfunction "NO1")
			(pintype "passive")
		)
		(pad "2" smd rect
			(at -1.372 -0.244)
			(size 0.75 0.3)
			(layers "F.Cu" "F.Mask" "F.Paste")
			(net 747 "/FPGA Config/FPGA_PWR.SCL")
			(pinfunction "NO2")
			(pintype "passive")
		)
		(pad "3" smd rect
			(at -1.372 0.256)
			(size 0.75 0.3)
			(layers "F.Cu" "F.Mask" "F.Paste")
			(net 526 "/Debug FTDI + VNA/FTDI.SCL")
			(pinfunction "NO3")
			(pintype "passive")
		)
		(pad "4" smd rect
			(at -1.372 0.757)
			(size 0.75 0.4)
			(layers "F.Cu" "F.Mask" "F.Paste")
			(net 1 "GND")
			(pinfunction "GND")
			(pintype "passive")
		)
		(pad "5" smd rect
			(at 1.377 0.757)
			(size 0.75 0.4)
			(layers "F.Cu" "F.Mask" "F.Paste")
			(net 405 "IN2")
			(pinfunction "IN2")
			(pintype "passive")
		)
		(pad "6" smd rect
			(at 1.377 0.256)
			(size 0.75 0.3)
			(layers "F.Cu" "F.Mask" "F.Paste")
			(net 404 "IN1")
			(pinfunction "IN1")
			(pintype "passive")
		)
		(pad "7" smd rect
			(at 1.377 -0.244)
			(size 0.75 0.3)
			(layers "F.Cu" "F.Mask" "F.Paste")
			(net 749 "/I^{2}C + I3C/PWR.SCL")
			(pinfunction "COM")
			(pintype "passive")
		)
		(pad "8" smd rect
			(at 1.377 -0.742)
			(size 0.75 0.4)
			(layers "F.Cu" "F.Mask" "F.Paste")
			(net 38 "+3V3_AON")
			(pinfunction "VCC")
			(pintype "passive")
		)
	)
	(footprint "antmicro-footprints:NetTie-2_SMD_Pad0.127mm"
		(layer "F.Cu")
		(at 245.663 150.451 180)
		(descr "Net tie, 2 pin, 0.127mm  SMD pads")
		(tags "net tie")
		(property "Reference" "NT14"
			(at -0.128 -1.345 0)
			(layer "F.SilkS")
			(hide yes)
			(effects
				(font
					(size 0.7 0.7)
					(thickness 0.15)
				)
				(justify right bottom)
			)
		)
		(property "Value" "Net-Tie_P0.127mm"
			(at 0 1.199 0)
			(layer "F.Fab")
			(effects
				(font
					(size 0.7 0.7)
					(thickness 0.15)
				)
				(justify right bottom)
			)
		)
		(property "MPN" ""
			(at 0 0 180)
			(unlocked yes)
			(layer "F.Fab")
			(hide yes)
			(effects
				(font
					(size 1 1)
					(thickness 0.15)
				)
			)
		)
		(property "Manufacturer" ""
			(at 0 0 180)
			(unlocked yes)
			(layer "F.Fab")
			(hide yes)
			(effects
				(font
					(size 1 1)
					(thickness 0.15)
				)
			)
		)
		(property "Author" "Antmicro"
			(at 0 0 180)
			(unlocked yes)
			(layer "F.Fab")
			(hide yes)
			(effects
				(font
					(size 1 1)
					(thickness 0.15)
				)
			)
		)
		(property "License" "Apache-2.0"
			(at 0 0 180)
			(unlocked yes)
			(layer "F.Fab")
			(hide yes)
			(effects
				(font
					(size 1 1)
					(thickness 0.15)
				)
			)
		)
		(property ki_fp_filters "Net*Tie*")
		(sheetname "/Supply/DC-DC IO/")
		(sheetfile "dc-dc-io.kicad_sch")
		(attr through_hole exclude_from_pos_files exclude_from_bom)
		(net_tie_pad_groups "1, 2")
		(fp_poly
			(pts
				(xy -0.0635 -0.0635) (xy 0.0625 -0.0635) (xy 0.0625 0.0635) (xy -0.0635 0.0635)
			)
			(stroke
				(width 0)
				(type solid)
			)
			(fill yes)
			(layer "F.Cu")
		)
		(fp_poly
			(pts
				(xy 0.2 -0.16) (xy 0.29 -0.07) (xy 0.29 0.07) (xy 0.2 0.16) (xy -0.2 0.16) (xy -0.29 0.07) (xy -0.29 -0.06)
				(xy -0.19 -0.16)
			)
			(stroke
				(width 0.05)
				(type solid)
			)
			(fill no)
			(layer "F.CrtYd")
		)
		(fp_text user "Author: Antmicro"
			(at -0.128 4.4 180)
			(layer "F.Fab")
			(effects
				(font
					(size 0.7 0.7)
					(thickness 0.15)
				)
				(justify left bottom)
			)
		)
		(fp_text user "License: Apache-2.0"
			(at -0.128 5.6 180)
			(layer "F.Fab")
			(effects
				(font
					(size 0.7 0.7)
					(thickness 0.15)
				)
				(justify left bottom)
			)
		)
		(fp_text user "${REFERENCE}"
			(at -0.128 3.2 180)
			(layer "F.Fab")
			(effects
				(font
					(size 0.7 0.7)
					(thickness 0.15)
				)
				(justify left bottom)
			)
		)
		(pad "1" smd roundrect
			(at -0.127 0)
			(size 0.127 0.127)
			(layers "F.Cu")
			(roundrect_rratio 0.5)
			(chamfer_ratio 0)
			(chamfer top_left bottom_left)
			(net 694 "/Supply/DC-DC IO/5V_SEN_-")
			(pinfunction "1")
			(pintype "passive")
		)
		(pad "2" smd roundrect
			(at 0.126 0 180)
			(size 0.127 0.127)
			(layers "F.Cu")
			(roundrect_rratio 0.5)
			(chamfer_ratio 0)
			(chamfer top_left bottom_left)
			(net 152 "+5V")
			(pinfunction "2")
			(pintype "passive")
		)
	)
	(footprint "antmicro-footprints:C_0402_1005Metric"
		(layer "F.Cu")
		(at 120.096 176.032 -90)
		(descr "Capacitor SMD 0402")
		(tags "capacitor SMD 0402")
		(property "Reference" "C284"
			(at -4.06 -0.41 90)
			(layer "F.SilkS")
			(effects
				(font
					(size 0.7 0.7)
					(thickness 0.15)
				)
				(justify right bottom)
			)
		)
		(property "Value" "C_10u_10V_0402"
			(at -1.022927 2.155213 90)
			(layer "F.Fab")
			(effects
				(font
					(size 0.7 0.7)
					(thickness 0.15)
				)
				(justify right bottom)
			)
		)
		(property "Datasheet" "https://www.murata.com/products/productdetail?partno=GRM155R61A106ME11%23"
			(at 0 0 270)
			(layer "F.Fab")
			(hide yes)
			(effects
				(font
					(size 1.27 1.27)
					(thickness 0.15)
				)
			)
		)
		(property "MPN" "GRM155R61A106ME11D"
			(at 0 0 270)
			(unlocked yes)
			(layer "F.Fab")
			(hide yes)
			(effects
				(font
					(size 1 1)
					(thickness 0.15)
				)
			)
		)
		(property "Manufacturer" "Murata"
			(at 0 0 270)
			(unlocked yes)
			(layer "F.Fab")
			(hide yes)
			(effects
				(font
					(size 1 1)
					(thickness 0.15)
				)
			)
		)
		(property "License" "Apache-2.0"
			(at 0 0 270)
			(unlocked yes)
			(layer "F.Fab")
			(hide yes)
			(effects
				(font
					(size 1 1)
					(thickness 0.15)
				)
			)
		)
		(property "Author" "Antmicro"
			(at 0 0 270)
			(unlocked yes)
			(layer "F.Fab")
			(hide yes)
			(effects
				(font
					(size 1 1)
					(thickness 0.15)
				)
			)
		)
		(property "Val" "10u"
			(at 0 0 270)
			(unlocked yes)
			(layer "F.Fab")
			(hide yes)
			(effects
				(font
					(size 1 1)
					(thickness 0.15)
				)
			)
		)
		(property "Voltage" "10V"
			(at 0 0 270)
			(unlocked yes)
			(layer "F.Fab")
			(hide yes)
			(effects
				(font
					(size 1 1)
					(thickness 0.15)
				)
			)
		)
		(property "Dielectric" "X5R"
			(at 0 0 270)
			(unlocked yes)
			(layer "F.Fab")
			(hide yes)
			(effects
				(font
					(size 1 1)
					(thickness 0.15)
				)
			)
		)
		(property "Public" ""
			(at 0 0 270)
			(unlocked yes)
			(layer "F.Fab")
			(hide yes)
			(effects
				(font
					(size 1 1)
					(thickness 0.15)
				)
			)
		)
		(sheetname "/HDMI + SD Card/")
		(sheetfile "hdmi-sd-card.kicad_sch")
		(attr smd)
		(fp_rect
			(start -0.925 -0.47)
			(end 0.925 0.47)
			(stroke
				(width 0.05)
				(type default)
			)
			(fill no)
			(layer "F.CrtYd")
		)
		(fp_line
			(start -0.494 0.248)
			(end -0.494 -0.25)
			(stroke
				(width 0.15)
				(type solid)
			)
			(layer "F.Fab")
		)
		(fp_line
			(start 0.504 0.248)
			(end -0.494 0.248)
			(stroke
				(width 0.15)
				(type solid)
			)
			(layer "F.Fab")
		)
		(fp_line
			(start -0.494 -0.25)
			(end 0.504 -0.25)
			(stroke
				(width 0.15)
				(type solid)
			)
			(layer "F.Fab")
		)
		(fp_line
			(start 0.504 -0.25)
			(end 0.504 0.248)
			(stroke
				(width 0.15)
				(type solid)
			)
			(layer "F.Fab")
		)
		(fp_text user "${REFERENCE}"
			(at -0.939 4.599 270)
			(layer "F.Fab")
			(effects
				(font
					(size 0.7 0.7)
					(thickness 0.15)
				)
				(justify left bottom)
			)
		)
		(fp_text user "Author: Antmicro"
			(at -0.939 3.399 270)
			(layer "F.Fab")
			(effects
				(font
					(size 0.7 0.7)
					(thickness 0.15)
				)
				(justify left bottom)
			)
		)
		(fp_text user "License: Apache-2.0"
			(at -0.939 5.799 270)
			(layer "F.Fab")
			(effects
				(font
					(size 0.7 0.7)
					(thickness 0.15)
				)
				(justify left bottom)
			)
		)
		(pad "1" smd roundrect
			(at -0.48 0 270)
			(size 0.59 0.64)
			(layers "F.Cu" "F.Mask" "F.Paste")
			(roundrect_rratio 0.25)
			(net 1 "GND")
			(pintype "passive")
		)
		(pad "2" smd roundrect
			(at 0.48 0 270)
			(size 0.59 0.64)
			(layers "F.Cu" "F.Mask" "F.Paste")
			(roundrect_rratio 0.25)
			(net 810 "/HDMI + SD Card/HDMI_VDD")
			(pintype "passive")
		)
	)
	(footprint "antmicro-footprints:X2SON8_1.4x1x0.32mm_P0.35mm"
		(layer "F.Cu")
		(at 147.934499 163.984)
		(property "Reference" "U16"
			(at -0.834499 1.791 90)
			(layer "F.SilkS")
			(effects
				(font
					(size 0.7 0.7)
					(thickness 0.15)
				)
				(justify left bottom)
			)
		)
		(property "Value" "TXS0102DQER"
			(at 0 1.929 0)
			(layer "F.Fab")
			(effects
				(font
					(size 0.7 0.7)
					(thickness 0.15)
				)
				(justify left bottom)
			)
		)
		(property "Datasheet" "https://www.ti.com/lit/ds/symlink/txs0102.pdf?ts=1637914596981&ref_url=https%253A%252F%252Fwww.ti.com%252Fstore%252Fti%252Fen%252Fp%252Fproduct%252F%253Fp%253DTXS0102DCTR%2526keyMatch%253DTXS0102DCTR%2526tisearch%253Dsearch-everything%2526usecase%253DOPN"
			(at 0 0 0)
			(layer "F.Fab")
			(hide yes)
			(effects
				(font
					(size 1.27 1.27)
					(thickness 0.15)
				)
			)
		)
		(property "MPN" "TXS0102DQER"
			(at 0 0 0)
			(unlocked yes)
			(layer "F.Fab")
			(hide yes)
			(effects
				(font
					(size 1 1)
					(thickness 0.15)
				)
			)
		)
		(property "Manufacturer" "Texas Instruments"
			(at 0 0 0)
			(unlocked yes)
			(layer "F.Fab")
			(hide yes)
			(effects
				(font
					(size 1 1)
					(thickness 0.15)
				)
			)
		)
		(property "Author" "Antmicro"
			(at 0 0 0)
			(unlocked yes)
			(layer "F.Fab")
			(hide yes)
			(effects
				(font
					(size 1 1)
					(thickness 0.15)
				)
			)
		)
		(property "License" "Apache-2.0"
			(at 0 0 0)
			(unlocked yes)
			(layer "F.Fab")
			(hide yes)
			(effects
				(font
					(size 1 1)
					(thickness 0.15)
				)
			)
		)
		(sheetname "/Debug FTDI + VNA/")
		(sheetfile "debug-ftdi.kicad_sch")
		(attr smd)
		(fp_line
			(start -0.6 -0.801)
			(end -0.6 -0.7)
			(stroke
				(width 0.15)
				(type solid)
			)
			(layer "F.SilkS")
		)
		(fp_line
			(start -0.6 0.7)
			(end -0.6 0.801)
			(stroke
				(width 0.15)
				(type solid)
			)
			(layer "F.SilkS")
		)
		(fp_line
			(start -0.6 0.801)
			(end -0.5 0.801)
			(stroke
				(width 0.15)
				(type solid)
			)
			(layer "F.SilkS")
		)
		(fp_line
			(start -0.402 -0.801)
			(end -0.6 -0.801)
			(stroke
				(width 0.15)
				(type solid)
			)
			(layer "F.SilkS")
		)
		(fp_line
			(start 0.598 -0.801)
			(end 0.498 -0.801)
			(stroke
				(width 0.15)
				(type solid)
			)
			(layer "F.SilkS")
		)
		(fp_line
			(start 0.598 -0.7)
			(end 0.598 -0.801)
			(stroke
				(width 0.15)
				(type solid)
			)
			(layer "F.SilkS")
		)
		(fp_line
			(start 0.598 0.7)
			(end 0.598 0.801)
			(stroke
				(width 0.15)
				(type solid)
			)
			(layer "F.SilkS")
		)
		(fp_line
			(start 0.598 0.801)
			(end 0.498 0.801)
			(stroke
				(width 0.15)
				(type solid)
			)
			(layer "F.SilkS")
		)
		(fp_circle
			(center -0.81 -0.77)
			(end -0.81 -0.72)
			(stroke
				(width 0.15)
				(type solid)
			)
			(fill yes)
			(layer "F.SilkS")
		)
		(fp_rect
			(start 0.75 -0.925)
			(end -0.75 0.925)
			(stroke
				(width 0.05)
				(type solid)
			)
			(fill no)
			(layer "F.CrtYd")
		)
		(fp_line
			(start -0.5 -0.729)
			(end -0.5 0.719)
			(stroke
				(width 0.15)
				(type solid)
			)
			(layer "F.Fab")
		)
		(fp_line
			(start -0.5 -0.724)
			(end 0.498 -0.724)
			(stroke
				(width 0.15)
				(type solid)
			)
			(layer "F.Fab")
		)
		(fp_line
			(start -0.5 0.724)
			(end 0.498 0.724)
			(stroke
				(width 0.15)
				(type solid)
			)
			(layer "F.Fab")
		)
		(fp_line
			(start 0.498 -0.719)
			(end 0.498 0.719)
			(stroke
				(width 0.15)
				(type solid)
			)
			(layer "F.Fab")
		)
		(fp_text user "${REFERENCE}"
			(at -0.95 3.929 0)
			(layer "F.Fab")
			(effects
				(font
					(size 0.7 0.7)
					(thickness 0.15)
				)
				(justify left bottom)
			)
		)
		(fp_text user "License: Apache-2.0"
			(at -0.95 6.329 0)
			(layer "F.Fab")
			(effects
				(font
					(size 0.7 0.7)
					(thickness 0.15)
				)
				(justify left bottom)
			)
		)
		(fp_text user "Author: Antmicro"
			(at -0.95 5.129 0)
			(layer "F.Fab")
			(effects
				(font
					(size 0.7 0.7)
					(thickness 0.15)
				)
				(justify left bottom)
			)
		)
		(pad "1" smd rect
			(at -0.43 -0.526 270)
			(size 0.17 0.5)
			(layers "F.Cu" "F.Mask" "F.Paste")
			(net 6 "/Debug FTDI + VNA/FTDI_3V3")
			(pinfunction "VCCA")
			(pintype "power_in")
		)
		(pad "2" smd rect
			(at -0.43 -0.175 270)
			(size 0.17 0.5)
			(layers "F.Cu" "F.Mask" "F.Paste")
			(net 790 "/Debug FTDI + VNA/FTDI_UART0_RX")
			(pinfunction "A1")
			(pintype "bidirectional")
		)
		(pad "3" smd rect
			(at -0.43 0.175 270)
			(size 0.17 0.5)
			(layers "F.Cu" "F.Mask" "F.Paste")
			(net 789 "/Debug FTDI + VNA/FTDI_UART0_TX")
			(pinfunction "A2")
			(pintype "bidirectional")
		)
		(pad "4" smd rect
			(at -0.43 0.526 270)
			(size 0.17 0.5)
			(layers "F.Cu" "F.Mask" "F.Paste")
			(net 1 "GND")
			(pinfunction "GND")
			(pintype "power_in")
		)
		(pad "5" smd rect
			(at 0.43 0.526 270)
			(size 0.17 0.5)
			(layers "F.Cu" "F.Mask" "F.Paste")
			(net 6 "/Debug FTDI + VNA/FTDI_3V3")
			(pinfunction "OE")
			(pintype "tri_state")
		)
		(pad "6" smd rect
			(at 0.43 0.175 270)
			(size 0.17 0.5)
			(layers "F.Cu" "F.Mask" "F.Paste")
			(net 375 "Net-(U16-B2)")
			(pinfunction "B2")
			(pintype "bidirectional")
		)
		(pad "7" smd rect
			(at 0.43 -0.175 270)
			(size 0.17 0.5)
			(layers "F.Cu" "F.Mask" "F.Paste")
			(net 373 "Net-(U16-B1)")
			(pinfunction "B1")
			(pintype "bidirectional")
		)
		(pad "8" smd rect
			(at 0.43 -0.526 270)
			(size 0.17 0.5)
			(layers "F.Cu" "F.Mask" "F.Paste")
			(net 151 "+3V3")
			(pinfunction "VCCB")
			(pintype "power_in")
		)
	)
)
